FILE_TYPE = CONNECTIVITY;
{Allegro Design Entry HDL 17.2-2016 S081 (4005846) 1/11/2022}
"PAGE_NUMBER" = 223;
0"NC";
1"PVNN_TERM_CPU0\g";
2"P3V3\g";
3"P3V3\g";
4"PVNN_TERM_CPU1\g";
5"PVNN_TERM_CPU1\g";
6"PVNN_TERM_CPU1\g";
7"P3V3_AUX\g";
8"P3V3_AUX\g";
9"P3V3_AUX\g";
10"P3V3\g";
11"P3V3\g";
12"PVNN_TERM_CPU0\g";
13"PVNN_TERM_CPU0\g";
14"P3V3_AUX\g";
15"GND\g";
16"GND\g";
17"GND\g";
18"GND\g";
19"GND\g";
20"GND\g";
21"GND\g";
22"GND\g";
23"GND\g";
24"GND\g";
25"GND\g";
26"FM_SMB_PEHPCPU1_PCIE_ALERT_R_N"CDS_PHYS_NET_NAME"FM_SMB_PEHPCPU1_PCIE_ALERT_R_N";
27"FM_SMB_CPU1_ALERT_R1";
28"FM_PEHPCPU1_ALERT_N";
29"FM_SMB_CPU0_ALERT_R1";
30"FM_PEHPCPU0_ALERT_N";
31"FM_SMB_PEHPCPU0_PCIE_ALERT_R_N"CDS_PHYS_NET_NAME"FM_SMB_PEHPCPU0_PCIE_ALERT_R_N";
32"FM_SMB_PEHPCPU0_PCIE_ALERT_N"CDS_PHYS_NET_NAME"FM_SMB_PEHPCPU0_PCIE_ALERT_N";
33"SMB_PEHPCPU0_GTL_SCL"CDS_PHYS_NET_NAME"SMB_PEHPCPU0_GTL_SCL";
34"SMB_PEHPCPU0_GTL_R_SCL"CDS_PHYS_NET_NAME"SMB_PEHPCPU0_GTL_R_SCL";
35"SMB_PEHPCPU0_GTL_SDA"CDS_PHYS_NET_NAME"SMB_PEHPCPU0_GTL_SDA";
36"SMB_PEHPCPU0_GTL_R_SDA"CDS_PHYS_NET_NAME"SMB_PEHPCPU0_GTL_R_SDA";
37"SMB_PEHPCPU1_GTL_R_SCL"CDS_PHYS_NET_NAME"SMB_PEHPCPU1_GTL_R_SCL";
38"SMB_PEHPCPU1_GTL_R_SDA"CDS_PHYS_NET_NAME"SMB_PEHPCPU1_GTL_R_SDA";
39"SMB_PEHPCPU1_GTL_SDA"CDS_PHYS_NET_NAME"SMB_PEHPCPU1_GTL_SDA";
40"SMB_PEHPCPU1_GTL_SCL"CDS_PHYS_NET_NAME"SMB_PEHPCPU1_GTL_SCL";
41"SMB_PEHPCPU0_LVC3_SDA_R0"CDS_PHYS_NET_NAME"SMB_PEHPCPU1_LVC3_SCL";
42"SMB_PEHPCPU0_LVC3_SDA"CDS_PHYS_NET_NAME"SMB_PEHPCPU0_LVC3_SDA";
43"SMB_PEHPCPU0_LVC3_SCL_R0"CDS_PHYS_NET_NAME"SMB_PEHPCPU1_LVC3_SCL";
44"SMB_PEHPCPU0_LVC3_SCL"CDS_PHYS_NET_NAME"SMB_PEHPCPU0_LVC3_SCL";
45"SMB_PEHPCPU1_LVC3_SDA_R0"CDS_PHYS_NET_NAME"SMB_PEHPCPU1_LVC3_SCL";
46"SMB_PEHPCPU1_LVC3_SDA"CDS_PHYS_NET_NAME"SMB_PEHPCPU1_LVC3_SDA";
47"SMB_PEHPCPU1_LVC3_SCL_R0"CDS_PHYS_NET_NAME"SMB_PEHPCPU1_LVC3_SCL";
48"SMB_PEHPCPU1_LVC3_SCL"CDS_PHYS_NET_NAME"SMB_PEHPCPU1_LVC3_SCL";
49"FM_SMB_PEHPCPU1_PCIE_ALERT_N"CDS_PHYS_NET_NAME"FM_SMB_PEHPCPU1_PCIE_ALERT_N";
50"TP_SMB_PEHPCPU0_EN"CDS_PHYS_NET_NAME"TP_SMB_PEHPCPU0_EN";
51"TP_SMB_PEHPCPU1_EN"CDS_PHYS_NET_NAME"TP_SMB_PEHPCPU1_EN";
52"FM_SMB_PEHPCPU1_PCIE_ALERT_N"CDS_PHYS_NET_NAME"FM_SMB_PEHPCPU1_PCIE_ALERT_N";
53"FM_SMB_PEHPCPU0_PCIE_ALERT_N"CDS_PHYS_NET_NAME"FM_SMB_PEHPCPU0_PCIE_ALERT_N";
%"UNIVERSAL_GND"
"1","(-1350,3500)","0","logical_power","I10";
;
CDS_LIB"logical_power"
HDL_POWER"GND";
"A"25;
%"Q_RES"
"1","(-5600,5425)","0","pure_quanta","I100";
;
PART_NUMBER"CS03322FB03"
VALUE"33.2"
TOLERANCE"1%"
MATERIAL"CHIP"
LOCATION"R962"
CDS_LIB"pure_quanta"
WATTAGE"1/16W"
PACK_TYPE"0402LF"
$SEC"1"
CDS_SEC"1";
"B"
$PN"2"38;
"A"
$PN"1"39;
%"Q_RES"
"1","(-5600,7125)","0","pure_quanta","I101";
;
PART_NUMBER"CS03322FB03"
VALUE"33.2"
TOLERANCE"1%"
MATERIAL"CHIP"
LOCATION"R960"
WATTAGE"1/16W"
PACK_TYPE"0402LF"
CDS_LIB"pure_quanta"
$SEC"1"
CDS_SEC"1";
"B"
$PN"2"34;
"A"
$PN"1"33;
%"Q_RES"
"1","(-5600,7025)","0","pure_quanta","I102";
;
PART_NUMBER"CS03322FB03"
MATERIAL"CHIP"
TOLERANCE"1%"
VALUE"33.2"
LOCATION"R909"
PACK_TYPE"0402LF"
WATTAGE"1/16W"
CDS_LIB"pure_quanta"
$SEC"1"
CDS_SEC"1";
"B"
$PN"2"36;
"A"
$PN"1"35;
%"MOSFET_NCH_DUAL"
"1","(-2550,3800)","0","pure_quanta","I104";
;
PART_NUMBER"BAM138K0003"
PART_TYPE"SMLF"
MATERIAL"IC"
VALUE"PJT138K"
LOCATION"Q15"
CDS_LIB"pure_quanta"
CDS_LMAN_SYM_OUTLINE"-150,150,150,-150"
SEC_TYPE""
NEEDS_NO_SIZE"TRUE"
SEC"1";
"D1"
$PN"6"29;
"G1"
$PN"2"31;
"S1"
$PN"1"21;
%"MOSFET_NCH_DUAL"
"1","(-2550,2500)","0","pure_quanta","I106";
;
PART_NUMBER"BAM138K0003"
PART_TYPE"SMLF"
MATERIAL"IC"
VALUE"PJT138K"
LOCATION"Q16"
CDS_LIB"pure_quanta"
CDS_LMAN_SYM_OUTLINE"-150,150,150,-150"
NEEDS_NO_SIZE"TRUE"
$SEC"1"
CDS_SEC"1";
"D1"
$PN"6"27;
"G1"
$PN"2"26;
"S1"
$PN"1"15;
%"MOSFET_NCH_DUAL"
"2","(-1400,3800)","0","pure_quanta","I108";
;
PART_NUMBER"BAM138K0003"
MATERIAL"IC"
PART_TYPE"SMLF"
VALUE"PJT138K"
LOCATION"Q15"
CDS_LIB"pure_quanta"
CDS_LMAN_SYM_OUTLINE"-150,150,150,-150"
NEEDS_NO_SIZE"TRUE"
$SEC"2"
CDS_SEC"2";
"S2"
$PN"4"25;
"G2"
$PN"5"29;
"D2"
$PN"3"30;
%"MOSFET_NCH_DUAL"
"2","(-1400,2500)","0","pure_quanta","I109";
;
PART_NUMBER"BAM138K0003"
MATERIAL"IC"
VALUE"PJT138K"
PART_TYPE"SMLF"
LOCATION"Q16"
CDS_LMAN_SYM_OUTLINE"-150,150,150,-150"
CDS_LIB"pure_quanta"
NEEDS_NO_SIZE"TRUE"
$SEC"2"
CDS_SEC"2";
"S2"
$PN"4"16;
"G2"
$PN"5"27;
"D2"
$PN"3"28;
%"UNIVERSAL_POWER"
"1","(-1350,3275)","0","logical_power","I11";
;
HDL_POWER"PVNN_TERM_CPU1"
CDS_LIB"logical_power";
"A"4;
%"Q_RES"
"2","(-1350,3025)","0","pure_quanta","I12";
;
PART_NUMBER"CS24702JB10"
WATTAGE"1/16W"
VALUE"4.7K"
TOLERANCE"5%"
PACK_TYPE"0402LF"
MATERIAL"CHIP"
$LOCATION"R1007"
CDS_LIB"pure_quanta"
CDS_LOCATION"R1007"
$SEC"1"
CDS_SEC"1";
"A"
$PN"1"4;
"B"
$PN"2"28;
%"UNIVERSAL_POWER"
"1","(-3000,7925)","0","logical_power","I16";
;
HDL_POWER"P3V3_AUX"
CDS_LIB"logical_power";
"A"14;
%"UNIVERSAL_GND"
"1","(-3000,7375)","0","logical_power","I17";
;
CDS_LIB"logical_power"
HDL_POWER"GND";
"A"24;
%"Q_CAP"
"1","(-3000,7600)","0","pure_quanta","I18";
;
PART_NUMBER"CH4104K1B00"
VALUE"0.1UF"
VOLTAGE"25V"
PACK_TYPE"0402"
MATERIAL"X7R"
TOLERANCE"10%"
$LOCATION"C561"
CDS_LIB"pure_quanta"
CDS_LOCATION"C561"
$SEC"1"
CDS_SEC"1";
"B"
$PN"2"24;
"A"
$PN"1"14;
%"UNIVERSAL_POWER"
"1","(-4350,7925)","0","logical_power","I19";
;
HDL_POWER"PVNN_TERM_CPU0"
CDS_LIB"logical_power";
"A"13;
%"Q_CAP"
"1","(-4350,7600)","2","pure_quanta","I20";
;
PART_NUMBER"CH4104K1B00"
MATERIAL"X7R"
TOLERANCE"10%"
VALUE"0.1UF"
VOLTAGE"25V"
PACK_TYPE"0402"
$LOCATION"C559"
CDS_LIB"pure_quanta"
CDS_LOCATION"C559"
$SEC"1"
CDS_SEC"1";
"B"
$PN"2"23;
"A"
$PN"1"13;
%"UNIVERSAL_GND"
"1","(-4350,7375)","0","logical_power","I21";
;
CDS_LIB"logical_power"
HDL_POWER"GND";
"A"23;
%"Q_RES"
"2","(-4925,7425)","2","pure_quanta","I22";
;
PART_NUMBER"CS12402FB01"
VALUE"240"
TOLERANCE"1%"
MATERIAL"CHIP"
PACK_TYPE"0402LF"
WATTAGE"1/16W"
$LOCATION"R911"
CDS_LIB"pure_quanta"
CDS_LOCATION"R911"
$SEC"1"
CDS_SEC"1";
"A"
$PN"1"12;
"B"
$PN"2"36;
%"UNIVERSAL_POWER"
"1","(-5125,7925)","0","logical_power","I23";
;
HDL_POWER"PVNN_TERM_CPU0"
CDS_LIB"logical_power";
"A"12;
%"Q_RES"
"2","(-5125,7425)","2","pure_quanta","I24";
;
PART_NUMBER"CS12402FB01"
VALUE"240"
WATTAGE"1/16W"
MATERIAL"CHIP"
PACK_TYPE"0402LF"
TOLERANCE"1%"
$LOCATION"R910"
CDS_LIB"pure_quanta"
CDS_LOCATION"R910"
$SEC"1"
CDS_SEC"1";
"A"
$PN"1"12;
"B"
$PN"2"34;
%"UNIVERSAL_POWER"
"1","(-3000,6325)","0","logical_power","I30";
;
HDL_POWER"P3V3_AUX"
CDS_LIB"logical_power";
"A"7;
%"Q_CAP"
"1","(-3000,6000)","0","pure_quanta","I31";
;
PART_NUMBER"CH4104K1B00"
TOLERANCE"10%"
MATERIAL"X7R"
PACK_TYPE"0402"
VOLTAGE"25V"
VALUE"0.1UF"
$LOCATION"C562"
CDS_LIB"pure_quanta"
CDS_LOCATION"C562"
$SEC"1"
CDS_SEC"1";
"B"
$PN"2"22;
"A"
$PN"1"7;
%"UNIVERSAL_GND"
"1","(-3000,5775)","0","logical_power","I32";
;
CDS_LIB"logical_power"
HDL_POWER"GND";
"A"22;
%"UNIVERSAL_POWER"
"1","(-2500,4575)","0","logical_power","I33";
;
HDL_POWER"P3V3"
CDS_LIB"logical_power";
"A"3;
%"Q_RES"
"2","(-2500,4325)","0","pure_quanta","I34";
;
PART_NUMBER"CS24702JB10"
TOLERANCE"5%"
MATERIAL"CHIP"
WATTAGE"1/16W"
VALUE"4.7K"
PACK_TYPE"0402LF"
$LOCATION"R1002"
CDS_LIB"pure_quanta"
CDS_LOCATION"R1002"
$SEC"1"
CDS_SEC"1";
"A"
$PN"1"3;
"B"
$PN"2"29;
%"UNIVERSAL_GND"
"1","(-2500,3500)","0","logical_power","I35";
;
CDS_LIB"logical_power"
HDL_POWER"GND";
"A"21;
%"UNIVERSAL_POWER"
"1","(-2500,3275)","0","logical_power","I37";
;
HDL_POWER"P3V3"
CDS_LIB"logical_power";
"A"2;
%"Q_RES"
"2","(-2500,3025)","0","pure_quanta","I38";
;
PART_NUMBER"CS24702JB10"
VALUE"4.7K"
MATERIAL"CHIP"
WATTAGE"1/16W"
TOLERANCE"5%"
PACK_TYPE"0402LF"
$LOCATION"R1003"
CDS_LIB"pure_quanta"
CDS_LOCATION"R1003"
$SEC"1"
CDS_SEC"1";
"A"
$PN"1"2;
"B"
$PN"2"27;
%"PCA9617ADP"
"1","(-3675,7075)","0","pure_quanta","I39";
;
PART_NUMBER"AL009617K02"
PART_TYPE"SMLF"
MATERIAL"IC"
VALUE"PCA9617ADP"
$LOCATION"U28"
SEC_TYPE""
CDS_LMAN_SYM_OUTLINE"-275,300,275,-300"
NEEDS_NO_SIZE"TRUE"
CDS_LIB"pure_quanta"
CDS_LOCATION"U28"
SEC"1";
"GND"
$PN"4"20;
"SCLB"
$PN"7"43;
"SDAB"
$PN"6"41;
"SDAA"
$PN"3"36;
"SCLA"
$PN"2"34;
"VCCB"
$PN"8"14;
"VCCA"
$PN"1"13;
"EN"
$PN"5"50;
%"UNIVERSAL_GND"
"1","(-4200,6650)","0","logical_power","I40";
;
CDS_LIB"logical_power"
HDL_POWER"GND";
"A"20;
%"UNIVERSAL_POWER"
"1","(-4350,6325)","0","logical_power","I41";
;
HDL_POWER"PVNN_TERM_CPU1"
CDS_LIB"logical_power";
"A"6;
%"Q_CAP"
"1","(-4350,6000)","2","pure_quanta","I42";
;
PART_NUMBER"CH4104K1B00"
VALUE"0.1UF"
TOLERANCE"10%"
PACK_TYPE"0402"
MATERIAL"X7R"
VOLTAGE"25V"
$LOCATION"C560"
CDS_LIB"pure_quanta"
CDS_LOCATION"C560"
$SEC"1"
CDS_SEC"1";
"B"
$PN"2"19;
"A"
$PN"1"6;
%"PCA9617ADP"
"1","(-3675,5475)","0","pure_quanta","I43";
;
PART_NUMBER"AL009617K02"
PART_TYPE"SMLF"
MATERIAL"IC"
VALUE"PCA9617ADP"
$LOCATION"U29"
CDS_LIB"pure_quanta"
NEEDS_NO_SIZE"TRUE"
CDS_LMAN_SYM_OUTLINE"-275,300,275,-300"
SEC_TYPE""
CDS_LOCATION"U29"
SEC"1";
"GND"
$PN"4"18;
"SCLB"
$PN"7"47;
"SDAB"
$PN"6"45;
"SDAA"
$PN"3"38;
"SCLA"
$PN"2"37;
"VCCB"
$PN"8"7;
"VCCA"
$PN"1"6;
"EN"
$PN"5"51;
%"UNIVERSAL_GND"
"1","(-4350,5775)","0","logical_power","I44";
;
CDS_LIB"logical_power"
HDL_POWER"GND";
"A"19;
%"UNIVERSAL_GND"
"1","(-4200,5050)","0","logical_power","I45";
;
CDS_LIB"logical_power"
HDL_POWER"GND";
"A"18;
%"Q_RES"
"2","(-4900,5825)","2","pure_quanta","I46";
;
PART_NUMBER"CS12402FB01"
MATERIAL"CHIP"
TOLERANCE"1%"
VALUE"240"
PACK_TYPE"0402LF"
WATTAGE"1/16W"
$LOCATION"R964"
CDS_LIB"pure_quanta"
CDS_LOCATION"R964"
$SEC"1"
CDS_SEC"1";
"A"
$PN"1"5;
"B"
$PN"2"38;
%"UNIVERSAL_POWER"
"1","(-5125,6325)","0","logical_power","I47";
;
HDL_POWER"PVNN_TERM_CPU1"
CDS_LIB"logical_power";
"A"5;
%"Q_RES"
"2","(-5125,5825)","2","pure_quanta","I48";
;
PART_NUMBER"CS12402FB01"
VALUE"240"
TOLERANCE"1%"
WATTAGE"1/16W"
MATERIAL"CHIP"
PACK_TYPE"0402LF"
$LOCATION"R963"
CDS_LIB"pure_quanta"
CDS_LOCATION"R963"
$SEC"1"
CDS_SEC"1";
"A"
$PN"1"5;
"B"
$PN"2"37;
%"UNIVERSAL_POWER"
"1","(-3975,4575)","0","logical_power","I51";
;
HDL_POWER"P3V3"
CDS_LIB"logical_power";
"A"11;
%"Q_RES"
"2","(-3975,4325)","0","pure_quanta","I52";
;
PART_NUMBER"CS24702JB10"
PACK_TYPE"0402LF"
MATERIAL"CHIP"
TOLERANCE"5%"
VALUE"4.7K"
WATTAGE"1/16W"
$LOCATION"R1000"
CDS_LIB"pure_quanta"
CDS_LOCATION"R1000"
$SEC"1"
CDS_SEC"1";
"A"
$PN"1"11;
"B"
$PN"2"31;
%"Q_RES"
"1","(-4325,3750)","0","pure_quanta","I53";
;
PART_NUMBER"CS00002JB13"
MATERIAL"CHIP"
PACK_TYPE"0402LF"
VALUE"0"
TOLERANCE"5%"
WATTAGE"1/16W"
$LOCATION"R998"
CDS_LIB"pure_quanta"
CDS_LOCATION"R998"
$SEC"1"
CDS_SEC"1";
"B"
$PN"2"31;
"A"
$PN"1"32;
%"UNIVERSAL_POWER"
"1","(-3975,3275)","0","logical_power","I54";
;
HDL_POWER"P3V3"
CDS_LIB"logical_power";
"A"10;
%"Q_RES"
"2","(-3975,3025)","0","pure_quanta","I55";
;
PART_NUMBER"CS24702JB10"
VALUE"4.7K"
MATERIAL"CHIP"
WATTAGE"1/16W"
TOLERANCE"5%"
PACK_TYPE"0402LF"
$LOCATION"R1001"
CDS_LIB"pure_quanta"
CDS_LOCATION"R1001"
$SEC"1"
CDS_SEC"1";
"A"
$PN"1"10;
"B"
$PN"2"26;
%"UNIVERSAL_GND"
"1","(-6425,2975)","0","logical_power","I63";
;
CDS_LIB"logical_power"
HDL_POWER"GND";
"A"17;
%"CONN3_210HP1030BR1"
"1","(-6725,3200)","2","pure_quanta","I64";
;
PART_NUMBER"DFHD03MS213"
PART_TYPE"THLF"
VALUE"CONN3_210-HP1-030BR1"
MATERIAL"IO"
$LOCATION"JP7"
CDS_LIB"pure_quanta"
CDS_LMAN_SYM_OUTLINE"-50,100,50,-100"
NEEDS_NO_SIZE"TRUE"
CDS_LOCATION"JP7"
$SEC"1"
CDS_SEC"1";
"1"
$PN"1"53;
"2"
$PN"2"17;
"3"
$PN"3"52;
%"UNIVERSAL_GND"
"1","(-1350,2200)","0","logical_power","I65";
;
CDS_LIB"logical_power"
HDL_POWER"GND";
"A"16;
%"UNIVERSAL_GND"
"1","(-2500,2200)","0","logical_power","I67";
;
CDS_LIB"logical_power"
HDL_POWER"GND";
"A"15;
%"Q_RES"
"1","(-5150,2450)","0","pure_quanta","I69";
;
PART_NUMBER"CS00002JB13"
TOLERANCE"5%"
VALUE"0"
WATTAGE"1/16W"
MATERIAL"CHIP"
PACK_TYPE"0402LF"
$LOCATION"R999"
CDS_LIB"pure_quanta"
CDS_LOCATION"R999"
$SEC"1"
CDS_SEC"1";
"B"
$PN"2"26;
"A"
$PN"1"49;
%"UNIVERSAL_POWER"
"1","(-1350,4575)","0","logical_power","I7";
;
HDL_POWER"PVNN_TERM_CPU0"
CDS_LIB"logical_power";
"A"1;
%"Q_RES"
"1","(-2000,5525)","0","pure_quanta","I76";
;
PART_NUMBER"CS03322FB03"
WATTAGE"1/16W"
PACK_TYPE"0402LF"
TOLERANCE"1%"
MATERIAL"CHIP"
VALUE"33.2"
$LOCATION"R2479"
CDS_LIB"pure_quanta"
CDS_LOCATION"R2479"
$SEC"1"
CDS_SEC"1";
"B"
$PN"2"48;
"A"
$PN"1"47;
%"Q_RES"
"1","(-2000,5425)","0","pure_quanta","I77";
;
PART_NUMBER"CS03322FB03"
VALUE"33.2"
TOLERANCE"1%"
MATERIAL"CHIP"
$LOCATION"R2480"
PACK_TYPE"0402LF"
WATTAGE"1/16W"
CDS_LIB"pure_quanta"
CDS_LOCATION"R2480"
$SEC"1"
CDS_SEC"1";
"B"
$PN"2"46;
"A"
$PN"1"45;
%"Q_RES"
"2","(-1350,4325)","0","pure_quanta","I8";
;
PART_NUMBER"CS24702JB10"
MATERIAL"CHIP"
WATTAGE"1/16W"
TOLERANCE"5%"
VALUE"4.7K"
PACK_TYPE"0402LF"
$LOCATION"R1006"
CDS_LIB"pure_quanta"
CDS_LOCATION"R1006"
$SEC"1"
CDS_SEC"1";
"A"
$PN"1"1;
"B"
$PN"2"30;
%"UNIVERSAL_POWER"
"1","(-750,6325)","0","logical_power","I80";
;
HDL_POWER"P3V3_AUX"
CDS_LIB"logical_power";
"A"9;
%"Q_RES"
"2","(-550,5975)","0","pure_quanta","I81";
;
PART_NUMBER"CS21002FB06"
VALUE"1K"
MATERIAL"CHIP"
PACK_TYPE"0402LF"
WATTAGE"1/16W"
TOLERANCE"1%"
$LOCATION"R968"
CDS_LIB"pure_quanta"
CDS_LOCATION"R968"
$SEC"1"
CDS_SEC"1";
"A"
$PN"1"9;
"B"
$PN"2"46;
%"Q_RES"
"2","(-750,5975)","0","pure_quanta","I82";
;
PART_NUMBER"CS21002FB06"
TOLERANCE"1%"
VALUE"1K"
MATERIAL"CHIP"
WATTAGE"1/16W"
PACK_TYPE"0402LF"
$LOCATION"R966"
CDS_LIB"pure_quanta"
CDS_LOCATION"R966"
$SEC"1"
CDS_SEC"1";
"A"
$PN"1"9;
"B"
$PN"2"48;
%"Q_RES"
"1","(-2000,7125)","0","pure_quanta","I88";
;
PART_NUMBER"CS03322FB03"
VALUE"33.2"
MATERIAL"CHIP"
TOLERANCE"1%"
PACK_TYPE"0402LF"
WATTAGE"1/16W"
$LOCATION"R2477"
CDS_LIB"pure_quanta"
CDS_LOCATION"R2477"
$SEC"1"
CDS_SEC"1";
"B"
$PN"2"44;
"A"
$PN"1"43;
%"Q_RES"
"1","(-2000,7025)","0","pure_quanta","I89";
;
PART_NUMBER"CS03322FB03"
MATERIAL"CHIP"
TOLERANCE"1%"
VALUE"33.2"
$LOCATION"R2478"
CDS_LIB"pure_quanta"
WATTAGE"1/16W"
PACK_TYPE"0402LF"
CDS_LOCATION"R2478"
$SEC"1"
CDS_SEC"1";
"B"
$PN"2"42;
"A"
$PN"1"41;
%"UNIVERSAL_POWER"
"1","(-750,7925)","0","logical_power","I92";
;
HDL_POWER"P3V3_AUX"
CDS_LIB"logical_power";
"A"8;
%"Q_RES"
"2","(-750,7575)","0","pure_quanta","I93";
;
PART_NUMBER"CS21002FB06"
WATTAGE"1/16W"
PACK_TYPE"0402LF"
MATERIAL"CHIP"
VALUE"1K"
TOLERANCE"1%"
$LOCATION"R965"
CDS_LIB"pure_quanta"
CDS_LOCATION"R965"
$SEC"1"
CDS_SEC"1";
"A"
$PN"1"8;
"B"
$PN"2"44;
%"Q_RES"
"2","(-550,7575)","0","pure_quanta","I94";
;
PART_NUMBER"CS21002FB06"
PACK_TYPE"0402LF"
MATERIAL"CHIP"
WATTAGE"1/16W"
TOLERANCE"1%"
VALUE"1K"
$LOCATION"R967"
CDS_LIB"pure_quanta"
CDS_LOCATION"R967"
$SEC"1"
CDS_SEC"1";
"A"
$PN"1"8;
"B"
$PN"2"42;
%"Q_RES"
"1","(-5600,5525)","0","pure_quanta","I99";
;
PART_NUMBER"CS03322FB03"
MATERIAL"CHIP"
TOLERANCE"1%"
VALUE"33.2"
LOCATION"R961"
PACK_TYPE"0402LF"
WATTAGE"1/16W"
CDS_LIB"pure_quanta"
$SEC"1"
CDS_SEC"1";
"B"
$PN"2"37;
"A"
$PN"1"40;
END.
